(kicad_pcb
	(version 20260206)
	(generator "pcbnew")
	(generator_version "10.0")
	(general
		(thickness 1.6)
		(legacy_teardrops no)
	)
	(paper "A4")
	(title_block
		(title "baseboard — 13948-1b.1110WZS1818.brd")
		(comment 1 "Honey Badger (Wiwynn) / footprints 391-397 of 2523")
	)
	(layers
		(0 "F.Cu" signal "TOP")
		(4 "In1.Cu" signal "L2GND")
		(6 "In2.Cu" signal "L3")
		(8 "In3.Cu" signal "L4VCC")
		(10 "In4.Cu" signal "L5VCC")
		(12 "In5.Cu" signal "L6")
		(14 "In6.Cu" signal "L7GND")
		(2 "B.Cu" signal "BOTTOM")
		(9 "F.Adhes" user "F.Adhesive")
		(11 "B.Adhes" user "B.Adhesive")
		(13 "F.Paste" user "Package Geometry/Pastemask Top")
		(15 "B.Paste" user "Package Geometry/Pastemask Bottom")
		(5 "F.SilkS" user "Ref Des/Silkscreen Top")
		(7 "B.SilkS" user "Ref Des/Silkscreen Bottom")
		(1 "F.Mask" user "Board Geometry/Soldermask Top")
		(3 "B.Mask" user "Board Geometry/Soldermask Bottom")
		(17 "Dwgs.User" user "User.Drawings")
		(19 "Cmts.User" user "User.Comments")
		(21 "Eco1.User" user "User.Eco1")
		(23 "Eco2.User" user "User.Eco2")
		(25 "Edge.Cuts" user "Board Geometry/Outline")
		(27 "Margin" user)
		(31 "F.CrtYd" user "Package Geometry/Place Bound Top")
		(29 "B.CrtYd" user "Package Geometry/Place Bound Bottom")
		(35 "F.Fab" user "Ref Des/Assembly Top")
		(33 "B.Fab" user "Ref Des/Assembly Bottom")
	)
	(footprint ""
		(layer "F.Cu")
		(at 131.318 -89.154 90)
		(property "Reference" "SC1265"
			(at 0 0 90)
			(layer "F.SilkS")
			(hide yes)
			(effects
				(font
					(size 1.27 1.27)
				)
			)
		)
		(property "Value" "SCD01U10V1KX-GP"
			(at -2.8321 -1.7399 90)
			(unlocked yes)
			(layer "F.Fab")
			(hide yes)
			(effects
				(font
					(size 1.016 1.016)
					(thickness 0.1524)
				)
			)
		)
		(property "Device Type" "C0201H13"
			(at -2.8321 -3.2639 90)
			(unlocked yes)
			(layer "F.Fab")
			(hide yes)
			(effects
				(font
					(size 1.016 1.016)
					(thickness 0.1524)
				)
			)
		)
		(duplicate_pad_numbers_are_jumpers no)
		(fp_rect
			(start -0.2794 0.6477)
			(end 0.2794 -0.6477)
			(stroke
				(width 0)
				(type default)
			)
			(fill no)
			(layer "F.CrtYd")
		)
		(fp_rect
			(start -0.2794 0.6477)
			(end 0.2794 -0.6477)
			(stroke
				(width 0)
				(type default)
			)
			(fill no)
			(layer "F.Fab")
		)
		(pad "1" smd custom
			(at 0 -0.2794 90)
			(size 0.0762 0.0762)
			(layers "F.Cu" "F.Mask" "F.Paste")
			(net "3X24_SAS_TX17_N")
			(options
				(clearance outline)
				(anchor circle)
			)
			(primitives
				(gr_poly
					(pts
						(arc
							(start 0.1524 -0.127)
							(mid 0.137521 -0.162921)
							(end 0.1016 -0.1778)
						)
						(arc
							(start -0.1016 -0.1778)
							(mid -0.137521 -0.162921)
							(end -0.1524 -0.127)
						)
						(arc
							(start -0.1524 0.127)
							(mid -0.137521 0.162921)
							(end -0.1016 0.1778)
						)
						(arc
							(start 0.1016 0.1778)
							(mid 0.137521 0.162921)
							(end 0.1524 0.127)
						)
					)
					(width 0)
					(fill yes)
				)
			)
		)
		(pad "2" smd custom
			(at 0 0.2794 90)
			(size 0.0762 0.0762)
			(layers "F.Cu" "F.Mask" "F.Paste")
			(net "SAS_EXP2CONN_TX_N_21")
			(options
				(clearance outline)
				(anchor circle)
			)
			(primitives
				(gr_poly
					(pts
						(arc
							(start 0.1524 -0.127)
							(mid 0.137521 -0.162921)
							(end 0.1016 -0.1778)
						)
						(arc
							(start -0.1016 -0.1778)
							(mid -0.137521 -0.162921)
							(end -0.1524 -0.127)
						)
						(arc
							(start -0.1524 0.127)
							(mid -0.137521 0.162921)
							(end -0.1016 0.1778)
						)
						(arc
							(start 0.1016 0.1778)
							(mid 0.137521 0.162921)
							(end 0.1524 0.127)
						)
					)
					(width 0)
					(fill yes)
				)
			)
		)
	)
	(footprint ""
		(layer "F.Cu")
		(at 288.408872 -218.512136)
		(property "Reference" "PR80"
			(at 0 0 0)
			(layer "F.SilkS")
			(hide yes)
			(effects
				(font
					(size 1.27 1.27)
				)
			)
		)
		(property "Value" "4K75R2F-1-GP"
			(at 0.064008 -3.993896 0)
			(unlocked yes)
			(layer "F.Fab")
			(hide yes)
			(effects
				(font
					(size 1.016 1.016)
					(thickness 0.1524)
				)
			)
		)
		(property "Device Type" "R402H16"
			(at 0.064008 -5.517896 0)
			(unlocked yes)
			(layer "F.Fab")
			(hide yes)
			(effects
				(font
					(size 1.016 1.016)
					(thickness 0.1524)
				)
			)
		)
		(duplicate_pad_numbers_are_jumpers no)
		(fp_line
			(start -0.508 -0.9398)
			(end -0.508 0.9398)
			(stroke
				(width 0.1524)
				(type default)
			)
			(layer "F.SilkS")
		)
		(fp_line
			(start 0.508 -0.9398)
			(end -0.508 -0.9398)
			(stroke
				(width 0.1524)
				(type default)
			)
			(layer "F.SilkS")
		)
		(fp_rect
			(start -0.508 0.9398)
			(end 0.508 -0.9398)
			(stroke
				(width 0)
				(type default)
			)
			(fill no)
			(layer "F.CrtYd")
		)
		(fp_rect
			(start -0.508 0.9398)
			(end 0.508 -0.9398)
			(stroke
				(width 0)
				(type default)
			)
			(fill no)
			(layer "F.Fab")
		)
		(pad "1" smd custom
			(at 0 -0.4445)
			(size 0.1397 0.1397)
			(layers "F.Cu" "F.Mask" "F.Paste")
			(net "TPS74801_1V53_STBY_FB")
			(options
				(clearance outline)
				(anchor circle)
			)
			(primitives
				(gr_poly
					(pts
						(arc
							(start -0.1778 -0.2794)
							(mid -0.249642 -0.249642)
							(end -0.2794 -0.1778)
						)
						(arc
							(start -0.2794 0.1778)
							(mid -0.249642 0.249642)
							(end -0.1778 0.2794)
						)
						(arc
							(start 0.1778 0.2794)
							(mid 0.249642 0.249642)
							(end 0.2794 0.1778)
						)
						(arc
							(start 0.2794 -0.1778)
							(mid 0.249642 -0.249642)
							(end 0.1778 -0.2794)
						)
					)
					(width 0)
					(fill yes)
				)
			)
		)
		(pad "2" smd custom
			(at 0 0.4445)
			(size 0.1397 0.1397)
			(layers "F.Cu" "F.Mask" "F.Paste")
			(net "GND")
			(options
				(clearance outline)
				(anchor circle)
			)
			(primitives
				(gr_poly
					(pts
						(arc
							(start -0.1778 -0.2794)
							(mid -0.249642 -0.249642)
							(end -0.2794 -0.1778)
						)
						(arc
							(start -0.2794 0.1778)
							(mid -0.249642 0.249642)
							(end -0.1778 0.2794)
						)
						(arc
							(start 0.1778 0.2794)
							(mid 0.249642 0.249642)
							(end 0.2794 0.1778)
						)
						(arc
							(start 0.2794 -0.1778)
							(mid 0.249642 -0.249642)
							(end 0.1778 -0.2794)
						)
					)
					(width 0)
					(fill yes)
				)
			)
		)
	)
	(footprint ""
		(layer "F.Cu")
		(at 117.856 -46.99 90)
		(property "Reference" "SR921"
			(at 0 0 90)
			(layer "F.SilkS")
			(hide yes)
			(effects
				(font
					(size 1.27 1.27)
				)
			)
		)
		(property "Value" "10KR2F-2-GP"
			(at 0.064008 -3.993896 90)
			(unlocked yes)
			(layer "F.Fab")
			(hide yes)
			(effects
				(font
					(size 1.016 1.016)
					(thickness 0.1524)
				)
			)
		)
		(property "Device Type" "R402H16"
			(at 0.064008 -5.517896 90)
			(unlocked yes)
			(layer "F.Fab")
			(hide yes)
			(effects
				(font
					(size 1.016 1.016)
					(thickness 0.1524)
				)
			)
		)
		(duplicate_pad_numbers_are_jumpers no)
		(fp_line
			(start 0.508 -0.9398)
			(end -0.508 -0.9398)
			(stroke
				(width 0.1524)
				(type default)
			)
			(layer "F.SilkS")
		)
		(fp_line
			(start -0.508 -0.9398)
			(end -0.508 0.9398)
			(stroke
				(width 0.1524)
				(type default)
			)
			(layer "F.SilkS")
		)
		(fp_rect
			(start -0.508 0.9398)
			(end 0.508 -0.9398)
			(stroke
				(width 0)
				(type default)
			)
			(fill no)
			(layer "F.CrtYd")
		)
		(fp_rect
			(start -0.508 0.9398)
			(end 0.508 -0.9398)
			(stroke
				(width 0)
				(type default)
			)
			(fill no)
			(layer "F.Fab")
		)
		(pad "1" smd custom
			(at 0 -0.4445 90)
			(size 0.1397 0.1397)
			(layers "F.Cu" "F.Mask" "F.Paste")
			(net "GND")
			(options
				(clearance outline)
				(anchor circle)
			)
			(primitives
				(gr_poly
					(pts
						(arc
							(start -0.1778 -0.2794)
							(mid -0.249642 -0.249642)
							(end -0.2794 -0.1778)
						)
						(arc
							(start -0.2794 0.1778)
							(mid -0.249642 0.249642)
							(end -0.1778 0.2794)
						)
						(arc
							(start 0.1778 0.2794)
							(mid 0.249642 0.249642)
							(end 0.2794 0.1778)
						)
						(arc
							(start 0.2794 -0.1778)
							(mid 0.249642 -0.249642)
							(end 0.1778 -0.2794)
						)
					)
					(width 0)
					(fill yes)
				)
			)
		)
		(pad "2" smd custom
			(at 0 0.4445 90)
			(size 0.1397 0.1397)
			(layers "F.Cu" "F.Mask" "F.Paste")
			(net "IOC_CLK_SEL0")
			(options
				(clearance outline)
				(anchor circle)
			)
			(primitives
				(gr_poly
					(pts
						(arc
							(start -0.1778 -0.2794)
							(mid -0.249642 -0.249642)
							(end -0.2794 -0.1778)
						)
						(arc
							(start -0.2794 0.1778)
							(mid -0.249642 0.249642)
							(end -0.1778 0.2794)
						)
						(arc
							(start 0.1778 0.2794)
							(mid 0.249642 0.249642)
							(end 0.2794 0.1778)
						)
						(arc
							(start 0.2794 -0.1778)
							(mid 0.249642 -0.249642)
							(end 0.1778 -0.2794)
						)
					)
					(width 0)
					(fill yes)
				)
			)
		)
	)
	(footprint ""
		(layer "F.Cu")
		(at 185.355992 -46.355)
		(property "Reference" "C271"
			(at 0 0 0)
			(layer "F.SilkS")
			(hide yes)
			(effects
				(font
					(size 1.27 1.27)
				)
			)
		)
		(property "Value" "SCD1U25V2KX-2-GP"
			(at 1.1811 -2.7051 0)
			(unlocked yes)
			(layer "F.Fab")
			(hide yes)
			(effects
				(font
					(size 1.016 1.016)
					(thickness 0.1524)
				)
			)
		)
		(property "Device Type" "C402H22"
			(at 1.1811 -4.2291 0)
			(unlocked yes)
			(layer "F.Fab")
			(hide yes)
			(effects
				(font
					(size 1.016 1.016)
					(thickness 0.1524)
				)
			)
		)
		(duplicate_pad_numbers_are_jumpers no)
		(fp_rect
			(start -0.4318 0.9525)
			(end 0.4318 -0.9525)
			(stroke
				(width 0)
				(type default)
			)
			(fill no)
			(layer "F.CrtYd")
		)
		(fp_rect
			(start -0.4318 0.9525)
			(end 0.4318 -0.9525)
			(stroke
				(width 0)
				(type default)
			)
			(fill no)
			(layer "F.Fab")
		)
		(pad "1" smd custom
			(at 0 -0.4445)
			(size 0.1524 0.1524)
			(layers "F.Cu" "F.Mask" "F.Paste")
			(net "P3V3_STBY")
			(options
				(clearance outline)
				(anchor circle)
			)
			(primitives
				(gr_poly
					(pts
						(arc
							(start 0.3048 -0.2032)
							(mid 0.275042 -0.275042)
							(end 0.2032 -0.3048)
						)
						(arc
							(start -0.2032 -0.3048)
							(mid -0.275042 -0.275042)
							(end -0.3048 -0.2032)
						)
						(arc
							(start -0.3048 0.2032)
							(mid -0.275042 0.275042)
							(end -0.2032 0.3048)
						)
						(arc
							(start 0.2032 0.3048)
							(mid 0.275042 0.275042)
							(end 0.3048 0.2032)
						)
					)
					(width 0)
					(fill yes)
				)
			)
		)
		(pad "2" smd custom
			(at 0 0.4445)
			(size 0.1524 0.1524)
			(layers "F.Cu" "F.Mask" "F.Paste")
			(net "GND")
			(options
				(clearance outline)
				(anchor circle)
			)
			(primitives
				(gr_poly
					(pts
						(arc
							(start 0.3048 -0.2032)
							(mid 0.275042 -0.275042)
							(end 0.2032 -0.3048)
						)
						(arc
							(start -0.2032 -0.3048)
							(mid -0.275042 -0.275042)
							(end -0.3048 -0.2032)
						)
						(arc
							(start -0.3048 0.2032)
							(mid -0.275042 0.275042)
							(end -0.2032 0.3048)
						)
						(arc
							(start 0.2032 0.3048)
							(mid 0.275042 0.275042)
							(end 0.3048 0.2032)
						)
					)
					(width 0)
					(fill yes)
				)
			)
		)
	)
	(footprint ""
		(layer "F.Cu")
		(at 90.31097 -112.014 180)
		(property "Reference" "SC1239"
			(at 0 0 180)
			(layer "F.SilkS")
			(hide yes)
			(effects
				(font
					(size 1.27 1.27)
				)
			)
		)
		(property "Value" "SCD1U6D3V1KX-GP"
			(at -2.8321 -1.7399 180)
			(unlocked yes)
			(layer "F.Fab")
			(hide yes)
			(effects
				(font
					(size 1.016 1.016)
					(thickness 0.1524)
				)
			)
		)
		(property "Device Type" "C0201H13"
			(at -2.8321 -3.2639 180)
			(unlocked yes)
			(layer "F.Fab")
			(hide yes)
			(effects
				(font
					(size 1.016 1.016)
					(thickness 0.1524)
				)
			)
		)
		(duplicate_pad_numbers_are_jumpers no)
		(fp_rect
			(start -0.2794 0.6477)
			(end 0.2794 -0.6477)
			(stroke
				(width 0)
				(type default)
			)
			(fill no)
			(layer "F.CrtYd")
		)
		(fp_rect
			(start -0.2794 0.6477)
			(end 0.2794 -0.6477)
			(stroke
				(width 0)
				(type default)
			)
			(fill no)
			(layer "F.Fab")
		)
		(pad "1" smd custom
			(at 0 -0.2794 180)
			(size 0.0762 0.0762)
			(layers "F.Cu" "F.Mask" "F.Paste")
			(net "P1V8_E")
			(options
				(clearance outline)
				(anchor circle)
			)
			(primitives
				(gr_poly
					(pts
						(arc
							(start 0.1524 -0.127)
							(mid 0.137521 -0.162921)
							(end 0.1016 -0.1778)
						)
						(arc
							(start -0.1016 -0.1778)
							(mid -0.137521 -0.162921)
							(end -0.1524 -0.127)
						)
						(arc
							(start -0.1524 0.127)
							(mid -0.137521 0.162921)
							(end -0.1016 0.1778)
						)
						(arc
							(start 0.1016 0.1778)
							(mid 0.137521 0.162921)
							(end 0.1524 0.127)
						)
					)
					(width 0)
					(fill yes)
				)
			)
		)
		(pad "2" smd custom
			(at 0 0.2794 180)
			(size 0.0762 0.0762)
			(layers "F.Cu" "F.Mask" "F.Paste")
			(net "GND")
			(options
				(clearance outline)
				(anchor circle)
			)
			(primitives
				(gr_poly
					(pts
						(arc
							(start 0.1524 -0.127)
							(mid 0.137521 -0.162921)
							(end 0.1016 -0.1778)
						)
						(arc
							(start -0.1016 -0.1778)
							(mid -0.137521 -0.162921)
							(end -0.1524 -0.127)
						)
						(arc
							(start -0.1524 0.127)
							(mid -0.137521 0.162921)
							(end -0.1016 0.1778)
						)
						(arc
							(start 0.1016 0.1778)
							(mid 0.137521 0.162921)
							(end 0.1524 0.127)
						)
					)
					(width 0)
					(fill yes)
				)
			)
		)
	)
	(footprint ""
		(layer "F.Cu")
		(at 102.616 -223.647 -90)
		(property "Reference" "R644"
			(at 0 0 270)
			(layer "F.SilkS")
			(hide yes)
			(effects
				(font
					(size 1.27 1.27)
				)
			)
		)
		(property "Value" "4K7R2F-GP"
			(at 0.064008 -3.993896 270)
			(unlocked yes)
			(layer "F.Fab")
			(hide yes)
			(effects
				(font
					(size 1.016 1.016)
					(thickness 0.1524)
				)
			)
		)
		(property "Device Type" "R402H16"
			(at 0.064008 -5.517896 270)
			(unlocked yes)
			(layer "F.Fab")
			(hide yes)
			(effects
				(font
					(size 1.016 1.016)
					(thickness 0.1524)
				)
			)
		)
		(duplicate_pad_numbers_are_jumpers no)
		(fp_line
			(start -0.508 -0.9398)
			(end -0.508 0.9398)
			(stroke
				(width 0.1524)
				(type default)
			)
			(layer "F.SilkS")
		)
		(fp_line
			(start 0.508 -0.9398)
			(end -0.508 -0.9398)
			(stroke
				(width 0.1524)
				(type default)
			)
			(layer "F.SilkS")
		)
		(fp_rect
			(start -0.508 0.9398)
			(end 0.508 -0.9398)
			(stroke
				(width 0)
				(type default)
			)
			(fill no)
			(layer "F.CrtYd")
		)
		(fp_rect
			(start -0.508 0.9398)
			(end 0.508 -0.9398)
			(stroke
				(width 0)
				(type default)
			)
			(fill no)
			(layer "F.Fab")
		)
		(pad "1" smd custom
			(at 0 -0.4445 270)
			(size 0.1397 0.1397)
			(layers "F.Cu" "F.Mask" "F.Paste")
			(net "P3V3_STBY")
			(options
				(clearance outline)
				(anchor circle)
			)
			(primitives
				(gr_poly
					(pts
						(arc
							(start -0.1778 -0.2794)
							(mid -0.249642 -0.249642)
							(end -0.2794 -0.1778)
						)
						(arc
							(start -0.2794 0.1778)
							(mid -0.249642 0.249642)
							(end -0.1778 0.2794)
						)
						(arc
							(start 0.1778 0.2794)
							(mid 0.249642 0.249642)
							(end 0.2794 0.1778)
						)
						(arc
							(start 0.2794 -0.1778)
							(mid 0.249642 -0.249642)
							(end 0.1778 -0.2794)
						)
					)
					(width 0)
					(fill yes)
				)
			)
		)
		(pad "2" smd custom
			(at 0 0.4445 270)
			(size 0.1397 0.1397)
			(layers "F.Cu" "F.Mask" "F.Paste")
			(net "IO_EXP_HDD_FAULT_A2")
			(options
				(clearance outline)
				(anchor circle)
			)
			(primitives
				(gr_poly
					(pts
						(arc
							(start -0.1778 -0.2794)
							(mid -0.249642 -0.249642)
							(end -0.2794 -0.1778)
						)
						(arc
							(start -0.2794 0.1778)
							(mid -0.249642 0.249642)
							(end -0.1778 0.2794)
						)
						(arc
							(start 0.1778 0.2794)
							(mid 0.249642 0.249642)
							(end 0.2794 0.1778)
						)
						(arc
							(start 0.2794 -0.1778)
							(mid 0.249642 -0.249642)
							(end 0.1778 -0.2794)
						)
					)
					(width 0)
					(fill yes)
				)
			)
		)
	)
	(footprint ""
		(layer "F.Cu")
		(at 307.8734 -149.05736 90)
		(property "Reference" "X10"
			(at 0 0 90)
			(layer "F.SilkS")
			(hide yes)
			(effects
				(font
					(size 1.27 1.27)
				)
			)
		)
		(property "Value" "OSC-125MHZ-3-GP"
			(at 0 -10.6172 90)
			(unlocked yes)
			(layer "F.Fab")
			(hide yes)
			(effects
				(font
					(size 1.016 1.016)
					(thickness 0.1524)
				)
			)
		)
		(property "Device Type" "SMD-OSC5H56"
			(at 0 -12.6492 90)
			(unlocked yes)
			(layer "F.Fab")
			(hide yes)
			(effects
				(font
					(size 1.016 1.016)
					(thickness 0.1524)
				)
			)
		)
		(duplicate_pad_numbers_are_jumpers no)
		(fp_line
			(start 3.7592 -3.3528)
			(end 3.7592 3.3528)
			(stroke
				(width 0.1524)
				(type default)
			)
			(layer "F.SilkS")
		)
		(fp_line
			(start -3.7592 -3.3528)
			(end 3.7592 -3.3528)
			(stroke
				(width 0.1524)
				(type default)
			)
			(layer "F.SilkS")
		)
		(fp_line
			(start 3.7592 3.3528)
			(end -3.7592 3.3528)
			(stroke
				(width 0.1524)
				(type default)
			)
			(layer "F.SilkS")
		)
		(fp_line
			(start -3.7592 3.3528)
			(end -3.7592 -3.3528)
			(stroke
				(width 0.1524)
				(type default)
			)
			(layer "F.SilkS")
		)
		(fp_line
			(start -2.416556 3.453638)
			(end -3.844544 3.453638)
			(stroke
				(width 0.3302)
				(type default)
			)
			(layer "F.SilkS")
		)
		(fp_line
			(start -3.844544 3.453638)
			(end -3.844544 1.789176)
			(stroke
				(width 0.3302)
				(type default)
			)
			(layer "F.SilkS")
		)
		(fp_poly
			(pts
				(xy -3.0734 3.9624) (xy -2.0066 3.9624) (xy -2.54 3.429)
			)
			(stroke
				(width 0)
				(type default)
			)
			(fill yes)
			(layer "F.SilkS")
		)
		(fp_rect
			(start -4.0132 3.6068)
			(end 4.0132 -3.6068)
			(stroke
				(width 0)
				(type default)
			)
			(fill no)
			(layer "F.CrtYd")
		)
		(fp_rect
			(start -4.0132 3.6068)
			(end 4.0132 -3.6068)
			(stroke
				(width 0)
				(type default)
			)
			(fill no)
			(layer "F.Fab")
		)
		(pad "1" smd rect
			(at -2.54 2.10058 90)
			(size 1.8034 2.0066)
			(layers "F.Cu" "F.Mask" "F.Paste")
			(net "OSC_OE")
		)
		(pad "2" smd rect
			(at 2.54 2.10058 90)
			(size 1.8034 2.0066)
			(layers "F.Cu" "F.Mask" "F.Paste")
			(net "GND")
		)
		(pad "3" smd rect
			(at 2.54 -2.10058 90)
			(size 1.8034 2.0066)
			(layers "F.Cu" "F.Mask" "F.Paste")
			(net "125_GTX")
		)
		(pad "4" smd rect
			(at -2.54 -2.10058 90)
			(size 1.8034 2.0066)
			(layers "F.Cu" "F.Mask" "F.Paste")
			(net "P3V3_STBY")
		)
		(zone
			(layer "F.Cu")
			(hatch none 0.5)
			(connect_pads
				(clearance 0)
			)
			(min_thickness 0.25)
			(keepout
				(tracks not_allowed)
				(vias allowed)
				(pads allowed)
				(copperpour not_allowed)
				(footprints allowed)
			)
			(placement
				(enabled no)
				(sheetname "")
			)
			(fill
				(thermal_gap 0.5)
				(thermal_bridge_width 0.5)
				(island_removal_mode 0)
			)
			(polygon
				(pts
					(xy 307.099462 -150.372318) (xy 308.647338 -150.372318) (xy 308.647338 -147.742402) (xy 307.099462 -147.742402)
				)
			)
		)
		(zone
			(layer "F.Cu")
			(hatch none 0.5)
			(connect_pads
				(clearance 0)
			)
			(min_thickness 0.25)
			(keepout
				(tracks allowed)
				(vias not_allowed)
				(pads allowed)
				(copperpour not_allowed)
				(footprints allowed)
			)
			(placement
				(enabled no)
				(sheetname "")
			)
			(fill
				(thermal_gap 0.5)
				(thermal_bridge_width 0.5)
				(island_removal_mode 0)
			)
			(polygon
				(pts
					(xy 310.97728 -147.41906) (xy 308.97068 -147.41906) (xy 308.97068 -145.61566) (xy 306.77612 -145.61566)
					(xy 306.77612 -147.41906) (xy 304.76952 -147.41906) (xy 304.76952 -150.69566) (xy 306.77612 -150.69566)
					(xy 306.77612 -152.49906) (xy 308.97068 -152.49906) (xy 308.97068 -150.69566) (xy 310.97728 -150.69566)
				)
			)
		)
	)
)
